(kicad_pcb
	(version 20260206)
	(generator "pcbnew")
	(generator_version "10.0")
	(general
		(thickness 1.6)
		(legacy_teardrops no)
	)
	(paper "A4")
	(title_block
		(title "01162023_DA0F0TEBIF0_F0T_Expander_BD_F_brd_V02_OCP.brd")
		(comment 1 "Grand Teton / footprints 2008-2014 of 9728")
	)
	(layers
		(0 "F.Cu" signal "TOP")
		(4 "In1.Cu" signal "GND")
		(6 "In2.Cu" signal "VCC")
		(8 "In3.Cu" signal "VCC1")
		(10 "In4.Cu" signal "GND1")
		(12 "In5.Cu" signal "IN1")
		(14 "In6.Cu" signal "GND2")
		(16 "In7.Cu" signal "IN2")
		(18 "In8.Cu" signal "GND3")
		(20 "In9.Cu" signal "IN3")
		(22 "In10.Cu" signal "GND4")
		(24 "In11.Cu" signal "IN4")
		(26 "In12.Cu" signal "GND5")
		(28 "In13.Cu" signal "IN5")
		(30 "In14.Cu" signal "GND6")
		(32 "In15.Cu" signal "IN6")
		(34 "In16.Cu" signal "GND7")
		(2 "B.Cu" signal "BOTTOM")
		(9 "F.Adhes" user "F.Adhesive")
		(11 "B.Adhes" user "B.Adhesive")
		(13 "F.Paste" user "Package Geometry/Pastemask Top")
		(15 "B.Paste" user "Package Geometry/Pastemask Bottom")
		(5 "F.SilkS" user "Ref Des/Silkscreen Top")
		(7 "B.SilkS" user "Ref Des/Silkscreen Bottom")
		(1 "F.Mask" user "Board Geometry/Soldermask Top")
		(3 "B.Mask" user "Board Geometry/Soldermask Bottom")
		(17 "Dwgs.User" user "User.Drawings")
		(19 "Cmts.User" user "User.Comments")
		(21 "Eco1.User" user "User.Eco1")
		(23 "Eco2.User" user "User.Eco2")
		(25 "Edge.Cuts" user "Board Geometry/Outline")
		(27 "Margin" user)
		(31 "F.CrtYd" user "Package Geometry/Place Bound Top")
		(29 "B.CrtYd" user "Package Geometry/Place Bound Bottom")
		(35 "F.Fab" user "Ref Des/Assembly Top")
		(33 "B.Fab" user "Ref Des/Assembly Bottom")
	)
	(footprint ""
		(layer "F.Cu")
		(at 382.468882 -230.43896)
		(property "Reference" "C2579"
			(at 0 0 0)
			(layer "F.SilkS")
			(hide yes)
			(effects
				(font
					(size 1.27 1.27)
				)
			)
		)
		(property "Value" ""
			(at 0 0 0)
			(layer "F.Fab")
			(effects
				(font
					(size 1.27 1.27)
				)
			)
		)
		(duplicate_pad_numbers_are_jumpers no)
		(fp_line
			(start -0.7874 -0.4064)
			(end 0.7874 -0.4064)
			(stroke
				(width 0.1524)
				(type default)
			)
			(layer "F.SilkS")
		)
		(fp_line
			(start -0.7874 0.4064)
			(end -0.7874 -0.4064)
			(stroke
				(width 0.1524)
				(type default)
			)
			(layer "F.SilkS")
		)
		(fp_line
			(start 0.7874 -0.4064)
			(end 0.7874 0.4064)
			(stroke
				(width 0.1524)
				(type default)
			)
			(layer "F.SilkS")
		)
		(fp_line
			(start 0.7874 0.4064)
			(end -0.7874 0.4064)
			(stroke
				(width 0.1524)
				(type default)
			)
			(layer "F.SilkS")
		)
		(fp_line
			(start -0.67945 -0.305054)
			(end -0.12065 -0.305054)
			(stroke
				(width 0.1)
				(type default)
			)
			(layer "F.Fab")
		)
		(fp_line
			(start -0.67945 0.3048)
			(end -0.67945 -0.305054)
			(stroke
				(width 0.1)
				(type default)
			)
			(layer "F.Fab")
		)
		(fp_line
			(start -0.12065 -0.305054)
			(end -0.12065 -0.2794)
			(stroke
				(width 0.1)
				(type default)
			)
			(layer "F.Fab")
		)
		(fp_line
			(start -0.12065 -0.2794)
			(end 0.12065 -0.2794)
			(stroke
				(width 0.1)
				(type default)
			)
			(layer "F.Fab")
		)
		(fp_line
			(start -0.12065 0.2794)
			(end -0.12065 0.3048)
			(stroke
				(width 0.1)
				(type default)
			)
			(layer "F.Fab")
		)
		(fp_line
			(start -0.12065 0.3048)
			(end -0.67945 0.3048)
			(stroke
				(width 0.1)
				(type default)
			)
			(layer "F.Fab")
		)
		(fp_line
			(start 0.120396 0.2794)
			(end -0.12065 0.2794)
			(stroke
				(width 0.1)
				(type default)
			)
			(layer "F.Fab")
		)
		(fp_line
			(start 0.120396 0.3048)
			(end 0.120396 0.2794)
			(stroke
				(width 0.1)
				(type default)
			)
			(layer "F.Fab")
		)
		(fp_line
			(start 0.12065 -0.3048)
			(end 0.67945 -0.3048)
			(stroke
				(width 0.1)
				(type default)
			)
			(layer "F.Fab")
		)
		(fp_line
			(start 0.12065 -0.2794)
			(end 0.12065 -0.3048)
			(stroke
				(width 0.1)
				(type default)
			)
			(layer "F.Fab")
		)
		(fp_line
			(start 0.67945 -0.3048)
			(end 0.67945 0.3048)
			(stroke
				(width 0.1)
				(type default)
			)
			(layer "F.Fab")
		)
		(fp_line
			(start 0.67945 0.3048)
			(end 0.120396 0.3048)
			(stroke
				(width 0.1)
				(type default)
			)
			(layer "F.Fab")
		)
		(pad "1" smd circle
			(at -0.40005 0)
			(size 0 0)
			(layers "F.Cu" "F.Mask" "F.Paste")
			(net "OSC_SDB_OUT")
		)
		(pad "2" smd circle
			(at 0.40005 0)
			(size 0 0)
			(layers "F.Cu" "F.Mask" "F.Paste")
			(net "GND")
		)
	)
	(footprint ""
		(layer "F.Cu")
		(at 103.11511 -367.488978 180)
		(property "Reference" "R6299"
			(at 0 0 180)
			(layer "F.SilkS")
			(hide yes)
			(effects
				(font
					(size 1.27 1.27)
				)
			)
		)
		(property "Value" ""
			(at 0 0 180)
			(layer "F.Fab")
			(effects
				(font
					(size 1.27 1.27)
				)
			)
		)
		(duplicate_pad_numbers_are_jumpers no)
		(fp_line
			(start 0.7874 0.4064)
			(end -0.7874 0.4064)
			(stroke
				(width 0.1524)
				(type default)
			)
			(layer "F.SilkS")
		)
		(fp_line
			(start 0.7874 -0.4064)
			(end 0.7874 0.4064)
			(stroke
				(width 0.1524)
				(type default)
			)
			(layer "F.SilkS")
		)
		(fp_line
			(start -0.7874 0.4064)
			(end -0.7874 -0.4064)
			(stroke
				(width 0.1524)
				(type default)
			)
			(layer "F.SilkS")
		)
		(fp_line
			(start -0.7874 -0.4064)
			(end 0.7874 -0.4064)
			(stroke
				(width 0.1524)
				(type default)
			)
			(layer "F.SilkS")
		)
		(fp_line
			(start 0.67945 0.3048)
			(end 0.120396 0.3048)
			(stroke
				(width 0.1)
				(type default)
			)
			(layer "F.Fab")
		)
		(fp_line
			(start 0.67945 -0.3048)
			(end 0.67945 0.3048)
			(stroke
				(width 0.1)
				(type default)
			)
			(layer "F.Fab")
		)
		(fp_line
			(start 0.12065 -0.2794)
			(end 0.12065 -0.3048)
			(stroke
				(width 0.1)
				(type default)
			)
			(layer "F.Fab")
		)
		(fp_line
			(start 0.12065 -0.3048)
			(end 0.67945 -0.3048)
			(stroke
				(width 0.1)
				(type default)
			)
			(layer "F.Fab")
		)
		(fp_line
			(start 0.120396 0.3048)
			(end 0.120396 0.2794)
			(stroke
				(width 0.1)
				(type default)
			)
			(layer "F.Fab")
		)
		(fp_line
			(start 0.120396 0.2794)
			(end -0.12065 0.2794)
			(stroke
				(width 0.1)
				(type default)
			)
			(layer "F.Fab")
		)
		(fp_line
			(start -0.12065 0.3048)
			(end -0.67945 0.3048)
			(stroke
				(width 0.1)
				(type default)
			)
			(layer "F.Fab")
		)
		(fp_line
			(start -0.12065 0.2794)
			(end -0.12065 0.3048)
			(stroke
				(width 0.1)
				(type default)
			)
			(layer "F.Fab")
		)
		(fp_line
			(start -0.12065 -0.2794)
			(end 0.12065 -0.2794)
			(stroke
				(width 0.1)
				(type default)
			)
			(layer "F.Fab")
		)
		(fp_line
			(start -0.12065 -0.305054)
			(end -0.12065 -0.2794)
			(stroke
				(width 0.1)
				(type default)
			)
			(layer "F.Fab")
		)
		(fp_line
			(start -0.67945 0.3048)
			(end -0.67945 -0.305054)
			(stroke
				(width 0.1)
				(type default)
			)
			(layer "F.Fab")
		)
		(fp_line
			(start -0.67945 -0.305054)
			(end -0.12065 -0.305054)
			(stroke
				(width 0.1)
				(type default)
			)
			(layer "F.Fab")
		)
		(pad "1" smd circle
			(at -0.40005 0 180)
			(size 0 0)
			(layers "F.Cu" "F.Mask" "F.Paste")
			(net "RST_MB_PERST_0_N")
		)
		(pad "2" smd circle
			(at 0.40005 0 180)
			(size 0 0)
			(layers "F.Cu" "F.Mask" "F.Paste")
			(net "GND")
		)
	)
	(footprint ""
		(layer "F.Cu")
		(at 229.471474 -136.669272 90)
		(property "Reference" "R4202"
			(at 0 0 90)
			(layer "F.SilkS")
			(hide yes)
			(effects
				(font
					(size 1.27 1.27)
				)
			)
		)
		(property "Value" ""
			(at 0 0 90)
			(layer "F.Fab")
			(effects
				(font
					(size 1.27 1.27)
				)
			)
		)
		(duplicate_pad_numbers_are_jumpers no)
		(fp_line
			(start 0.7874 -0.4064)
			(end 0.7874 0.4064)
			(stroke
				(width 0.1524)
				(type default)
			)
			(layer "F.SilkS")
		)
		(fp_line
			(start -0.7874 -0.4064)
			(end 0.7874 -0.4064)
			(stroke
				(width 0.1524)
				(type default)
			)
			(layer "F.SilkS")
		)
		(fp_line
			(start 0.7874 0.4064)
			(end -0.7874 0.4064)
			(stroke
				(width 0.1524)
				(type default)
			)
			(layer "F.SilkS")
		)
		(fp_line
			(start -0.7874 0.4064)
			(end -0.7874 -0.4064)
			(stroke
				(width 0.1524)
				(type default)
			)
			(layer "F.SilkS")
		)
		(fp_line
			(start -0.12065 -0.305054)
			(end -0.12065 -0.2794)
			(stroke
				(width 0.1)
				(type default)
			)
			(layer "F.Fab")
		)
		(fp_line
			(start -0.67945 -0.305054)
			(end -0.12065 -0.305054)
			(stroke
				(width 0.1)
				(type default)
			)
			(layer "F.Fab")
		)
		(fp_line
			(start 0.67945 -0.3048)
			(end 0.67945 0.3048)
			(stroke
				(width 0.1)
				(type default)
			)
			(layer "F.Fab")
		)
		(fp_line
			(start 0.12065 -0.3048)
			(end 0.67945 -0.3048)
			(stroke
				(width 0.1)
				(type default)
			)
			(layer "F.Fab")
		)
		(fp_line
			(start 0.12065 -0.2794)
			(end 0.12065 -0.3048)
			(stroke
				(width 0.1)
				(type default)
			)
			(layer "F.Fab")
		)
		(fp_line
			(start -0.12065 -0.2794)
			(end 0.12065 -0.2794)
			(stroke
				(width 0.1)
				(type default)
			)
			(layer "F.Fab")
		)
		(fp_line
			(start 0.120396 0.2794)
			(end -0.12065 0.2794)
			(stroke
				(width 0.1)
				(type default)
			)
			(layer "F.Fab")
		)
		(fp_line
			(start -0.12065 0.2794)
			(end -0.12065 0.3048)
			(stroke
				(width 0.1)
				(type default)
			)
			(layer "F.Fab")
		)
		(fp_line
			(start 0.67945 0.3048)
			(end 0.120396 0.3048)
			(stroke
				(width 0.1)
				(type default)
			)
			(layer "F.Fab")
		)
		(fp_line
			(start 0.120396 0.3048)
			(end 0.120396 0.2794)
			(stroke
				(width 0.1)
				(type default)
			)
			(layer "F.Fab")
		)
		(fp_line
			(start -0.12065 0.3048)
			(end -0.67945 0.3048)
			(stroke
				(width 0.1)
				(type default)
			)
			(layer "F.Fab")
		)
		(fp_line
			(start -0.67945 0.3048)
			(end -0.67945 -0.305054)
			(stroke
				(width 0.1)
				(type default)
			)
			(layer "F.Fab")
		)
		(pad "1" smd circle
			(at -0.40005 0 90)
			(size 0 0)
			(layers "F.Cu" "F.Mask" "F.Paste")
			(net "GND")
		)
		(pad "2" smd circle
			(at 0.40005 0 90)
			(size 0 0)
			(layers "F.Cu" "F.Mask" "F.Paste")
			(net "CLK_CK440_PEX_SMB_ADDR0")
		)
	)
	(footprint ""
		(layer "F.Cu")
		(at 122.809254 -26.03373)
		(property "Reference" "R4060"
			(at 0 0 0)
			(layer "F.SilkS")
			(hide yes)
			(effects
				(font
					(size 1.27 1.27)
				)
			)
		)
		(property "Value" ""
			(at 0 0 0)
			(layer "F.Fab")
			(effects
				(font
					(size 1.27 1.27)
				)
			)
		)
		(duplicate_pad_numbers_are_jumpers no)
		(fp_line
			(start -0.7874 -0.4064)
			(end 0.7874 -0.4064)
			(stroke
				(width 0.1524)
				(type default)
			)
			(layer "F.SilkS")
		)
		(fp_line
			(start -0.7874 0.4064)
			(end -0.7874 -0.4064)
			(stroke
				(width 0.1524)
				(type default)
			)
			(layer "F.SilkS")
		)
		(fp_line
			(start 0.7874 -0.4064)
			(end 0.7874 0.4064)
			(stroke
				(width 0.1524)
				(type default)
			)
			(layer "F.SilkS")
		)
		(fp_line
			(start 0.7874 0.4064)
			(end -0.7874 0.4064)
			(stroke
				(width 0.1524)
				(type default)
			)
			(layer "F.SilkS")
		)
		(fp_line
			(start -0.67945 -0.305054)
			(end -0.12065 -0.305054)
			(stroke
				(width 0.1)
				(type default)
			)
			(layer "F.Fab")
		)
		(fp_line
			(start -0.67945 0.3048)
			(end -0.67945 -0.305054)
			(stroke
				(width 0.1)
				(type default)
			)
			(layer "F.Fab")
		)
		(fp_line
			(start -0.12065 -0.305054)
			(end -0.12065 -0.2794)
			(stroke
				(width 0.1)
				(type default)
			)
			(layer "F.Fab")
		)
		(fp_line
			(start -0.12065 -0.2794)
			(end 0.12065 -0.2794)
			(stroke
				(width 0.1)
				(type default)
			)
			(layer "F.Fab")
		)
		(fp_line
			(start -0.12065 0.2794)
			(end -0.12065 0.3048)
			(stroke
				(width 0.1)
				(type default)
			)
			(layer "F.Fab")
		)
		(fp_line
			(start -0.12065 0.3048)
			(end -0.67945 0.3048)
			(stroke
				(width 0.1)
				(type default)
			)
			(layer "F.Fab")
		)
		(fp_line
			(start 0.120396 0.2794)
			(end -0.12065 0.2794)
			(stroke
				(width 0.1)
				(type default)
			)
			(layer "F.Fab")
		)
		(fp_line
			(start 0.120396 0.3048)
			(end 0.120396 0.2794)
			(stroke
				(width 0.1)
				(type default)
			)
			(layer "F.Fab")
		)
		(fp_line
			(start 0.12065 -0.3048)
			(end 0.67945 -0.3048)
			(stroke
				(width 0.1)
				(type default)
			)
			(layer "F.Fab")
		)
		(fp_line
			(start 0.12065 -0.2794)
			(end 0.12065 -0.3048)
			(stroke
				(width 0.1)
				(type default)
			)
			(layer "F.Fab")
		)
		(fp_line
			(start 0.67945 -0.3048)
			(end 0.67945 0.3048)
			(stroke
				(width 0.1)
				(type default)
			)
			(layer "F.Fab")
		)
		(fp_line
			(start 0.67945 0.3048)
			(end 0.120396 0.3048)
			(stroke
				(width 0.1)
				(type default)
			)
			(layer "F.Fab")
		)
		(pad "1" smd circle
			(at -0.40005 0)
			(size 0 0)
			(layers "F.Cu" "F.Mask" "F.Paste")
			(net "P3V3_AUX")
		)
		(pad "2" smd circle
			(at 0.40005 0)
			(size 0 0)
			(layers "F.Cu" "F.Mask" "F.Paste")
			(net "PRSNT_SSD4_R_N")
		)
	)
	(footprint ""
		(layer "F.Cu")
		(at 15.18539 -308.28488 180)
		(property "Reference" "PR166"
			(at 0 0 180)
			(layer "F.SilkS")
			(hide yes)
			(effects
				(font
					(size 1.27 1.27)
				)
			)
		)
		(property "Value" ""
			(at 0 0 180)
			(layer "F.Fab")
			(effects
				(font
					(size 1.27 1.27)
				)
			)
		)
		(duplicate_pad_numbers_are_jumpers no)
		(fp_line
			(start 0.7874 0.4064)
			(end -0.7874 0.4064)
			(stroke
				(width 0.1524)
				(type default)
			)
			(layer "F.SilkS")
		)
		(fp_line
			(start 0.7874 -0.4064)
			(end 0.7874 0.4064)
			(stroke
				(width 0.1524)
				(type default)
			)
			(layer "F.SilkS")
		)
		(fp_line
			(start -0.7874 0.4064)
			(end -0.7874 -0.4064)
			(stroke
				(width 0.1524)
				(type default)
			)
			(layer "F.SilkS")
		)
		(fp_line
			(start -0.7874 -0.4064)
			(end 0.7874 -0.4064)
			(stroke
				(width 0.1524)
				(type default)
			)
			(layer "F.SilkS")
		)
		(fp_line
			(start 0.67945 0.3048)
			(end 0.120396 0.3048)
			(stroke
				(width 0.1)
				(type default)
			)
			(layer "F.Fab")
		)
		(fp_line
			(start 0.67945 -0.3048)
			(end 0.67945 0.3048)
			(stroke
				(width 0.1)
				(type default)
			)
			(layer "F.Fab")
		)
		(fp_line
			(start 0.12065 -0.2794)
			(end 0.12065 -0.3048)
			(stroke
				(width 0.1)
				(type default)
			)
			(layer "F.Fab")
		)
		(fp_line
			(start 0.12065 -0.3048)
			(end 0.67945 -0.3048)
			(stroke
				(width 0.1)
				(type default)
			)
			(layer "F.Fab")
		)
		(fp_line
			(start 0.120396 0.3048)
			(end 0.120396 0.2794)
			(stroke
				(width 0.1)
				(type default)
			)
			(layer "F.Fab")
		)
		(fp_line
			(start 0.120396 0.2794)
			(end -0.12065 0.2794)
			(stroke
				(width 0.1)
				(type default)
			)
			(layer "F.Fab")
		)
		(fp_line
			(start -0.12065 0.3048)
			(end -0.67945 0.3048)
			(stroke
				(width 0.1)
				(type default)
			)
			(layer "F.Fab")
		)
		(fp_line
			(start -0.12065 0.2794)
			(end -0.12065 0.3048)
			(stroke
				(width 0.1)
				(type default)
			)
			(layer "F.Fab")
		)
		(fp_line
			(start -0.12065 -0.2794)
			(end 0.12065 -0.2794)
			(stroke
				(width 0.1)
				(type default)
			)
			(layer "F.Fab")
		)
		(fp_line
			(start -0.12065 -0.305054)
			(end -0.12065 -0.2794)
			(stroke
				(width 0.1)
				(type default)
			)
			(layer "F.Fab")
		)
		(fp_line
			(start -0.67945 0.3048)
			(end -0.67945 -0.305054)
			(stroke
				(width 0.1)
				(type default)
			)
			(layer "F.Fab")
		)
		(fp_line
			(start -0.67945 -0.305054)
			(end -0.12065 -0.305054)
			(stroke
				(width 0.1)
				(type default)
			)
			(layer "F.Fab")
		)
		(pad "1" smd circle
			(at -0.40005 0 180)
			(size 0 0)
			(layers "F.Cu" "F.Mask" "F.Paste")
			(net "SH_P1V25_PEX0_FB_P")
		)
		(pad "2" smd circle
			(at 0.40005 0 180)
			(size 0 0)
			(layers "F.Cu" "F.Mask" "F.Paste")
			(net "P1V25_PEX0_FB")
		)
	)
	(footprint ""
		(layer "F.Cu")
		(at 260.451346 -334.010254 90)
		(property "Reference" "R6798"
			(at 0 0 90)
			(layer "F.SilkS")
			(hide yes)
			(effects
				(font
					(size 1.27 1.27)
				)
			)
		)
		(property "Value" ""
			(at 0 0 90)
			(layer "F.Fab")
			(effects
				(font
					(size 1.27 1.27)
				)
			)
		)
		(duplicate_pad_numbers_are_jumpers no)
		(fp_line
			(start 0.7874 -0.4064)
			(end 0.7874 0.4064)
			(stroke
				(width 0.1524)
				(type default)
			)
			(layer "F.SilkS")
		)
		(fp_line
			(start -0.7874 -0.4064)
			(end 0.7874 -0.4064)
			(stroke
				(width 0.1524)
				(type default)
			)
			(layer "F.SilkS")
		)
		(fp_line
			(start 0.7874 0.4064)
			(end -0.7874 0.4064)
			(stroke
				(width 0.1524)
				(type default)
			)
			(layer "F.SilkS")
		)
		(fp_line
			(start -0.7874 0.4064)
			(end -0.7874 -0.4064)
			(stroke
				(width 0.1524)
				(type default)
			)
			(layer "F.SilkS")
		)
		(fp_line
			(start -0.12065 -0.305054)
			(end -0.12065 -0.2794)
			(stroke
				(width 0.1)
				(type default)
			)
			(layer "F.Fab")
		)
		(fp_line
			(start -0.67945 -0.305054)
			(end -0.12065 -0.305054)
			(stroke
				(width 0.1)
				(type default)
			)
			(layer "F.Fab")
		)
		(fp_line
			(start 0.67945 -0.3048)
			(end 0.67945 0.3048)
			(stroke
				(width 0.1)
				(type default)
			)
			(layer "F.Fab")
		)
		(fp_line
			(start 0.12065 -0.3048)
			(end 0.67945 -0.3048)
			(stroke
				(width 0.1)
				(type default)
			)
			(layer "F.Fab")
		)
		(fp_line
			(start 0.12065 -0.2794)
			(end 0.12065 -0.3048)
			(stroke
				(width 0.1)
				(type default)
			)
			(layer "F.Fab")
		)
		(fp_line
			(start -0.12065 -0.2794)
			(end 0.12065 -0.2794)
			(stroke
				(width 0.1)
				(type default)
			)
			(layer "F.Fab")
		)
		(fp_line
			(start 0.120396 0.2794)
			(end -0.12065 0.2794)
			(stroke
				(width 0.1)
				(type default)
			)
			(layer "F.Fab")
		)
		(fp_line
			(start -0.12065 0.2794)
			(end -0.12065 0.3048)
			(stroke
				(width 0.1)
				(type default)
			)
			(layer "F.Fab")
		)
		(fp_line
			(start 0.67945 0.3048)
			(end 0.120396 0.3048)
			(stroke
				(width 0.1)
				(type default)
			)
			(layer "F.Fab")
		)
		(fp_line
			(start 0.120396 0.3048)
			(end 0.120396 0.2794)
			(stroke
				(width 0.1)
				(type default)
			)
			(layer "F.Fab")
		)
		(fp_line
			(start -0.12065 0.3048)
			(end -0.67945 0.3048)
			(stroke
				(width 0.1)
				(type default)
			)
			(layer "F.Fab")
		)
		(fp_line
			(start -0.67945 0.3048)
			(end -0.67945 -0.305054)
			(stroke
				(width 0.1)
				(type default)
			)
			(layer "F.Fab")
		)
		(pad "1" smd rect
			(at -0.40005 0 270)
			(size 0.4572 0.508)
			(layers "F.Cu" "F.Mask" "F.Paste")
			(net "HSC_OC_VOL")
		)
		(pad "2" smd rect
			(at 0.40005 0 270)
			(size 0.4572 0.508)
			(layers "F.Cu" "F.Mask" "F.Paste")
			(net "GND")
		)
	)
	(footprint ""
		(layer "F.Cu")
		(at 387.580632 -121.919746)
		(property "Reference" "C679"
			(at 0 0 0)
			(layer "F.SilkS")
			(hide yes)
			(effects
				(font
					(size 1.27 1.27)
				)
			)
		)
		(property "Value" ""
			(at 0 0 0)
			(layer "F.Fab")
			(effects
				(font
					(size 1.27 1.27)
				)
			)
		)
		(duplicate_pad_numbers_are_jumpers no)
		(fp_line
			(start -0.299974 -0.150114)
			(end 0.299974 -0.150114)
			(stroke
				(width 0.1)
				(type default)
			)
			(layer "F.Fab")
		)
		(fp_line
			(start -0.299974 0.150114)
			(end -0.299974 -0.150114)
			(stroke
				(width 0.1)
				(type default)
			)
			(layer "F.Fab")
		)
		(fp_line
			(start 0.299974 -0.150114)
			(end 0.299974 0.150114)
			(stroke
				(width 0.1)
				(type default)
			)
			(layer "F.Fab")
		)
		(fp_line
			(start 0.299974 0.150114)
			(end -0.299974 0.150114)
			(stroke
				(width 0.1)
				(type default)
			)
			(layer "F.Fab")
		)
		(pad "1" smd rect
			(at -0.2667 0)
			(size 0.3048 0.381)
			(layers "F.Cu" "F.Mask" "F.Paste")
			(net "P5E_PEX3_STN1_TX_DP<25>")
		)
		(pad "2" smd rect
			(at 0.2667 0)
			(size 0.3048 0.381)
			(layers "F.Cu" "F.Mask" "F.Paste")
			(net "P5E_PEX3_STN1_TX_C_DP<25>")
		)
	)
)
